# BASEBOARD_FAB2 (Tioga Pass) — schematic netlist excerpt (pin names and nets, part order shuffled) for the footprints in the layout excerpt that follows; sources: Cadence DE-HDL packaged netlist, KiCad conversion of Wiwynn_Tioga_Pass_MB.brd

C3N17  CAP_A  1.0UF 6.3V 10% X6S  pkg 0402V  page 132 : A = PVNN_PCH_STBY ; B = GND
R2N10  RES  4.75K 1% EMPTY  pkg 0402  page 126 : A = P3V3_STBY ; B = FM_PCH_BMC_THERMTRIP_EXI_STRAP_

U6W6  TTL1G126_A  74HC1G126 IC  pkg SOT  page 176
  OE  = SPA_MID_DBG1_TX_EN
  A  = SPA_MID_DBG_TX
  Y  = SPA_MID_DBG1_TX_R

(kicad_pcb
	(version 20260206)
	(generator "pcbnew")
	(generator_version "10.0")
	(general
		(thickness 1.6)
		(legacy_teardrops no)
	)
	(paper "A4")
	(title_block
		(title "Wiwynn_Tioga_Pass_MB.brd")
		(comment 1 "Tioga Pass / footprints 2787-2789 of 4770")
	)
	(layers
		(0 "F.Cu" signal "TOP")
		(4 "In1.Cu" signal "L2GND")
		(6 "In2.Cu" signal "L3")
		(8 "In3.Cu" signal "L4GND")
		(10 "In4.Cu" signal "L5")
		(12 "In5.Cu" signal "L6GND")
		(14 "In6.Cu" signal "L7VCC")
		(16 "In7.Cu" signal "L8VCC")
		(18 "In8.Cu" signal "L9GND")
		(20 "In9.Cu" signal "L10")
		(22 "In10.Cu" signal "L11GND")
		(24 "In11.Cu" signal "L12")
		(26 "In12.Cu" signal "L13GND")
		(2 "B.Cu" signal "BOTTOM")
		(9 "F.Adhes" user "F.Adhesive")
		(11 "B.Adhes" user "B.Adhesive")
		(13 "F.Paste" user "Package Geometry/Pastemask Top")
		(15 "B.Paste" user "Package Geometry/Pastemask Bottom")
		(5 "F.SilkS" user "Ref Des/Silkscreen Top")
		(7 "B.SilkS" user "Ref Des/Silkscreen Bottom")
		(1 "F.Mask" user "Board Geometry/Soldermask Top")
		(3 "B.Mask" user "Board Geometry/Soldermask Bottom")
		(17 "Dwgs.User" user "User.Drawings")
		(19 "Cmts.User" user "User.Comments")
		(21 "Eco1.User" user "User.Eco1")
		(23 "Eco2.User" user "User.Eco2")
		(25 "Edge.Cuts" user "Board Geometry/Outline")
		(27 "Margin" user)
		(31 "F.CrtYd" user "Package Geometry/Place Bound Top")
		(29 "B.CrtYd" user "Package Geometry/Place Bound Bottom")
		(35 "F.Fab" user "Ref Des/Assembly Top")
		(33 "B.Fab" user "Ref Des/Assembly Bottom")
	)
	(footprint ""
		(layer "B.Cu")
		(at 385.33705 -107.85475 90)
		(property "Reference" "C3N17"
			(at 0 0 90)
			(layer "B.SilkS")
			(hide yes)
			(effects
				(font
					(size 1.27 1.27)
				)
				(justify mirror)
			)
		)
		(property "Value" ""
			(at 0 0 90)
			(layer "B.Fab")
			(effects
				(font
					(size 1.27 1.27)
				)
				(justify mirror)
			)
		)
		(duplicate_pad_numbers_are_jumpers no)
		(fp_rect
			(start 0.2794 0.9144)
			(end -0.2794 -0.1143)
			(stroke
				(width 0)
				(type default)
			)
			(fill no)
			(layer "B.CrtYd")
		)
		(fp_line
			(start 0.2794 -0.1143)
			(end -0.2794 -0.1143)
			(stroke
				(width 0.1)
				(type default)
			)
			(layer "B.Fab")
		)
		(fp_line
			(start -0.2794 -0.1143)
			(end -0.2794 0.9144)
			(stroke
				(width 0.1)
				(type default)
			)
			(layer "B.Fab")
		)
		(fp_line
			(start 0.2794 0.9144)
			(end 0.2794 -0.1143)
			(stroke
				(width 0.1)
				(type default)
			)
			(layer "B.Fab")
		)
		(fp_line
			(start -0.2794 0.9144)
			(end 0.2794 0.9144)
			(stroke
				(width 0.1)
				(type default)
			)
			(layer "B.Fab")
		)
		(pad "1" smd custom
			(at 0 0)
			(size 0.10414 0.10414)
			(layers "B.Cu" "B.Mask" "B.Paste")
			(net "PVNN_PCH_STBY")
			(options
				(clearance outline)
				(anchor circle)
			)
			(primitives
				(gr_poly
					(pts
						(xy -0.20828 -0.08636) (xy -0.20828 0.08636) (xy -0.08636 0.20828) (xy 0.086614 0.20828) (xy 0.20828 0.086614)
						(xy 0.20828 -0.08636) (xy 0.08636 -0.20828) (xy -0.08636 -0.20828)
					)
					(width 0)
					(fill yes)
				)
			)
		)
		(pad "2" smd custom
			(at 0 0.8001)
			(size 0.10414 0.10414)
			(layers "B.Cu" "B.Mask" "B.Paste")
			(net "GND")
			(options
				(clearance outline)
				(anchor circle)
			)
			(primitives
				(gr_poly
					(pts
						(xy -0.20828 -0.08636) (xy -0.20828 0.08636) (xy -0.08636 0.20828) (xy 0.086614 0.20828) (xy 0.20828 0.086614)
						(xy 0.20828 -0.08636) (xy 0.08636 -0.20828) (xy -0.08636 -0.20828)
					)
					(width 0)
					(fill yes)
				)
			)
		)
		(zone
			(layer "B.Cu")
			(hatch none 0.5)
			(connect_pads
				(clearance 0)
			)
			(min_thickness 0.25)
			(keepout
				(tracks allowed)
				(vias not_allowed)
				(pads allowed)
				(copperpour not_allowed)
				(footprints allowed)
			)
			(placement
				(enabled no)
				(sheetname "")
			)
			(fill
				(thermal_gap 0.5)
				(thermal_bridge_width 0.5)
				(island_removal_mode 0)
			)
			(polygon
				(pts
					(xy 385.5466 -107.94238) (xy 385.9276 -107.94238) (xy 385.9276 -107.76712) (xy 385.5466 -107.766866)
				)
			)
		)
		(zone
			(layer "B.Cu")
			(hatch none 0.5)
			(connect_pads
				(clearance 0)
			)
			(min_thickness 0.25)
			(keepout
				(tracks not_allowed)
				(vias allowed)
				(pads allowed)
				(copperpour not_allowed)
				(footprints allowed)
			)
			(placement
				(enabled no)
				(sheetname "")
			)
			(fill
				(thermal_gap 0.5)
				(thermal_bridge_width 0.5)
				(island_removal_mode 0)
			)
			(polygon
				(pts
					(xy 385.5466 -107.94238) (xy 385.9276 -107.94238) (xy 385.9276 -107.76712) (xy 385.5466 -107.766866)
				)
			)
		)
	)
	(footprint ""
		(layer "B.Cu")
		(at 500.253 -148.1582 -90)
		(property "Reference" "U6W6"
			(at 0.14986 2.621788 270)
			(unlocked yes)
			(layer "B.SilkS")
			(effects
				(font
					(size 1.27 0.964946)
					(thickness 0.000001)
				)
				(justify left mirror)
			)
		)
		(property "Value" ""
			(at 0 0 90)
			(layer "B.Fab")
			(effects
				(font
					(size 1.27 1.27)
				)
				(justify mirror)
			)
		)
		(duplicate_pad_numbers_are_jumpers no)
		(fp_circle
			(center 0.4699 -0.8382)
			(end 0.4699 -0.9652)
			(stroke
				(width 0.254)
				(type default)
			)
			(fill no)
			(layer "B.SilkS")
		)
		(fp_poly
			(pts
				(xy -0.21463 -0.450088) (xy -1.56337 -0.450088) (xy -1.56337 1.75006) (xy -0.21463 1.75006)
			)
			(stroke
				(width 0)
				(type default)
			)
			(fill no)
			(layer "B.CrtYd")
		)
		(fp_line
			(start -1.56337 1.75006)
			(end -0.21463 1.75006)
			(stroke
				(width 0.1)
				(type default)
			)
			(layer "B.Fab")
		)
		(fp_line
			(start -0.21463 1.75006)
			(end -0.21463 -0.450088)
			(stroke
				(width 0.1)
				(type default)
			)
			(layer "B.Fab")
		)
		(fp_line
			(start -1.56337 -0.450088)
			(end -1.56337 1.75006)
			(stroke
				(width 0.1)
				(type default)
			)
			(layer "B.Fab")
		)
		(fp_line
			(start -0.21463 -0.450088)
			(end -1.56337 -0.450088)
			(stroke
				(width 0.1)
				(type default)
			)
			(layer "B.Fab")
		)
		(fp_circle
			(center 0.4699 -0.8382)
			(end 0.4699 -0.9652)
			(stroke
				(width 0.254)
				(type default)
			)
			(fill no)
			(layer "B.Fab")
		)
		(pad "1" smd rect
			(at 0 0 90)
			(size 1.016 0.381)
			(layers "B.Cu" "B.Mask" "B.Paste")
			(net "SPA_MID_DBG1_TX_EN")
		)
		(pad "2" smd rect
			(at 0 0.649986 90)
			(size 1.016 0.381)
			(layers "B.Cu" "B.Mask" "B.Paste")
			(net "SPA_MID_DBG_TX")
		)
		(pad "3" smd rect
			(at 0 1.299972 90)
			(size 1.016 0.381)
			(layers "B.Cu" "B.Mask" "B.Paste")
			(net "GND")
		)
		(pad "4" smd rect
			(at -1.778 1.299972 90)
			(size 1.016 0.381)
			(layers "B.Cu" "B.Mask" "B.Paste")
			(net "SPA_MID_DBG1_TX_R")
		)
		(pad "5" smd rect
			(at -1.778 0 90)
			(size 1.016 0.381)
			(layers "B.Cu" "B.Mask" "B.Paste")
			(net "P3V3_STBY")
		)
	)
	(footprint ""
		(layer "B.Cu")
		(at 404.5585 -97.917 -90)
		(property "Reference" "R2N10"
			(at 0 0 90)
			(layer "B.SilkS")
			(hide yes)
			(effects
				(font
					(size 1.27 1.27)
				)
				(justify mirror)
			)
		)
		(property "Value" ""
			(at 0 0 90)
			(layer "B.Fab")
			(effects
				(font
					(size 1.27 1.27)
				)
				(justify mirror)
			)
		)
		(duplicate_pad_numbers_are_jumpers no)
		(fp_poly
			(pts
				(xy 0.2794 -0.1016) (xy -0.2794 -0.1016) (xy -0.2794 0.9906) (xy 0.2794 0.9906)
			)
			(stroke
				(width 0)
				(type default)
			)
			(fill no)
			(layer "B.CrtYd")
		)
		(fp_line
			(start -0.2794 0.9906)
			(end -0.2794 -0.1016)
			(stroke
				(width 0.1)
				(type default)
			)
			(layer "B.Fab")
		)
		(fp_line
			(start 0.2794 0.9906)
			(end -0.2794 0.9906)
			(stroke
				(width 0.1)
				(type default)
			)
			(layer "B.Fab")
		)
		(fp_line
			(start -0.2794 -0.1016)
			(end 0.2794 -0.1016)
			(stroke
				(width 0.1)
				(type default)
			)
			(layer "B.Fab")
		)
		(fp_line
			(start 0.2794 -0.1016)
			(end 0.2794 0.9906)
			(stroke
				(width 0.1)
				(type default)
			)
			(layer "B.Fab")
		)
		(pad "1" smd rect
			(at 0 0 90)
			(size 0.508 0.508)
			(layers "B.Cu" "B.Mask" "B.Paste")
			(net "P3V3_STBY")
		)
		(pad "2" smd rect
			(at 0 0.889 90)
			(size 0.508 0.508)
			(layers "B.Cu" "B.Mask" "B.Paste")
			(net "FM_PCH_BMC_THERMTRIP_EXI_STRAP_")
		)
		(zone
			(layer "B.Cu")
			(hatch none 0.5)
			(connect_pads
				(clearance 0)
			)
			(min_thickness 0.25)
			(keepout
				(tracks not_allowed)
				(vias allowed)
				(pads allowed)
				(copperpour not_allowed)
				(footprints allowed)
			)
			(placement
				(enabled no)
				(sheetname "")
			)
			(fill
				(thermal_gap 0.5)
				(thermal_bridge_width 0.5)
				(island_removal_mode 0)
			)
			(polygon
				(pts
					(xy 403.9235 -97.663) (xy 403.9235 -98.171) (xy 404.3045 -98.171) (xy 404.3045 -97.663)
				)
			)
		)
		(zone
			(layer "B.Cu")
			(hatch none 0.5)
			(connect_pads
				(clearance 0)
			)
			(min_thickness 0.25)
			(keepout
				(tracks allowed)
				(vias not_allowed)
				(pads allowed)
				(copperpour not_allowed)
				(footprints allowed)
			)
			(placement
				(enabled no)
				(sheetname "")
			)
			(fill
				(thermal_gap 0.5)
				(thermal_bridge_width 0.5)
				(island_removal_mode 0)
			)
			(polygon
				(pts
					(xy 404.3045 -97.663) (xy 404.3045 -98.171) (xy 403.9235 -98.171) (xy 403.9235 -97.663)
				)
			)
		)
	)
)
